FILE_TYPE = MULTI_PHYS_TABLE;

PART 'LCMXO3LF2100C5BG256C'

{========================================================================================}
:VALUE                    | PART_TYPE | MATERIAL | PART_NUMBER    = STANDARD | LIFECYCLE | PART_NUMBER   | JEDEC_TYPE         | DESCRIPTION                                | MANUFTR | MANUF_PN                 | RD_CMPLS_LVL | CMPLS_LVL | FROM_PJ     | CLASS | DIP_SMD | DATA                                    | EE_CHECK_LIST | FP_ECN                       | PSL | CREATOR | STATUS | MSD  | ESD_CDM | ESD_HBM | ESD_MM | PIN_LENGTH_SHORT_PIN | PIN_LENGTH_LONG_PIN | CREATEDAY  ;
{========================================================================================}
 'LCMXO3LF-2100C-5BG256C' | 'SMLF'    | 'IC'     | 'AJ021000T03'(!) = ''       | ''        | 'AJ021000T03' |'BGA256_0-8_14X14'| 'ICOTHER(256P)LCMXO3LF-2100C-5BG256(CABGA' | 'LSC'   | 'LCMXO3LF-2100C-5BG256C' | 'EP(V1)'     | ''        | 'MF5-STEVE' | 'IC'  | ''      | 'LSC_LCMXO3LF-2100C-5BG256C.pdf'        | ''            | ''                           | ''  | ''      | ''     | 'NA' | 'NA'    | 'NA'    | 'NA'   | '0 MILS'             | '0 MILS'            | '20180326'
 'LCMXO3LF-2100C-5BG256C' | 'SMLF'    | 'EMPTY'  | 'AJ021000T03'(!) = ''       | ''        | 'AJ021000T03' |'BGA256_0-8_14X14'| 'ICOTHER(256P)LCMXO3LF-2100C-5BG256(CABGA' | 'LSC'   | 'LCMXO3LF-2100C-5BG256C' | 'EP(V1)'     | ''        | 'MF5-STEVE' | 'IC'  | ''      | 'LSC_LCMXO3LF-2100C-5BG256C.pdf'        | ''            | ''                           | ''  | ''      | ''     | 'NA' | 'NA'    | 'NA'    | 'NA'   | '0 MILS'             | '0 MILS'            | '20180326'
 'LCMXO3LF-2100C-5BG256C' | 'SMLF'    | 'IC'     | 'AR0A5WS6016'(!) = ''       | ''        | 'AR0A5WS6016' |'BGA256_0-8_14X14'| 'PROG IC(256P)LCMXO3LF-2100C-5BG25(0XD303' | 'LSC'   | 'LCMXO3LF-2100C-5BG256C' | 'EP(V1)'     | 'EP(V1)'  | 'A5W-ALVIN' | 'IC'  | ''      | 'LSC_LCMXO3LF-2100C-5BG256C_0XD303.pdf' | ''            | 'LCMXO3LF-2100C-5BG256C.msg' | ''  | ''      | ''     | ''   | ''      | ''      | ''     | '0 MILS'             | '0 MILS'            | '20230505'
 'LCMXO3LF-2100C-5BG256C' | 'SMLF'    | 'EMPTY'  | 'AR0A5WS6016'(!) = ''       | ''        | 'AR0A5WS6016' |'BGA256_0-8_14X14'| 'PROG IC(256P)LCMXO3LF-2100C-5BG25(0XD303' | 'LSC'   | 'LCMXO3LF-2100C-5BG256C' | 'EP(V1)'     | 'EP(V1)'  | 'A5W-ALVIN' | 'IC'  | ''      | 'LSC_LCMXO3LF-2100C-5BG256C_0XD303.pdf' | ''            | 'LCMXO3LF-2100C-5BG256C.msg' | ''  | ''      | ''     | ''   | ''      | ''      | ''     | '0 MILS'             | '0 MILS'            | '20230505'

END_PART

END.

